# SCM (Grand Teton) — schematic netlist excerpt (pin names and nets, part order shuffled) for the footprints in the layout excerpt that follows; sources: Cadence DE-HDL packaged netlist, KiCad conversion of 12092022_DA0F0TMDCD0_F0T_Management_Board_D_brd_V3_OCP.brd

C68  Q_CAP  0.1UF 25V 10% X7R  pkg 0402  page 16 : A = P1V0_STBY_PLAVDD ; B = GND
R882  Q_RES  0 5% CHIP  pkg 0402LF  page 50 : A = REAR_AC_PWR_BTN ; B = REAR_AC_PWR_BMC_BTN_N

(kicad_pcb
	(version 20260206)
	(generator "pcbnew")
	(generator_version "10.0")
	(general
		(thickness 1.6)
		(legacy_teardrops no)
	)
	(paper "A4")
	(title_block
		(title "12092022_DA0F0TMDCD0_F0T_Management_Board_D_brd_V3_OCP.brd")
		(comment 1 "Grand Teton / footprints 1205-1206 of 1440")
	)
	(layers
		(0 "F.Cu" signal "TOP")
		(4 "In1.Cu" signal "GND")
		(6 "In2.Cu" signal "IN1")
		(8 "In3.Cu" signal "GND1")
		(10 "In4.Cu" signal "IN2")
		(12 "In5.Cu" signal "VCC")
		(14 "In6.Cu" signal "VCC1")
		(16 "In7.Cu" signal "IN3")
		(18 "In8.Cu" signal "GND2")
		(20 "In9.Cu" signal "IN4")
		(22 "In10.Cu" signal "GND3")
		(2 "B.Cu" signal "BOTTOM")
		(9 "F.Adhes" user "F.Adhesive")
		(11 "B.Adhes" user "B.Adhesive")
		(13 "F.Paste" user "Package Geometry/Pastemask Top")
		(15 "B.Paste" user "Package Geometry/Pastemask Bottom")
		(5 "F.SilkS" user "Ref Des/Silkscreen Top")
		(7 "B.SilkS" user "Ref Des/Silkscreen Bottom")
		(1 "F.Mask" user "Board Geometry/Soldermask Top")
		(3 "B.Mask" user "Board Geometry/Soldermask Bottom")
		(17 "Dwgs.User" user "User.Drawings")
		(19 "Cmts.User" user "User.Comments")
		(21 "Eco1.User" user "User.Eco1")
		(23 "Eco2.User" user "User.Eco2")
		(25 "Edge.Cuts" user "Board Geometry/Outline")
		(27 "Margin" user)
		(31 "F.CrtYd" user "Package Geometry/Place Bound Top")
		(29 "B.CrtYd" user "Package Geometry/Place Bound Bottom")
		(35 "F.Fab" user "Ref Des/Assembly Top")
		(33 "B.Fab" user "Ref Des/Assembly Bottom")
	)
	(footprint ""
		(layer "B.Cu")
		(at 61.2648 -42.3926 -90)
		(property "Reference" "C68"
			(at 0 0 90)
			(layer "B.SilkS")
			(hide yes)
			(effects
				(font
					(size 1.27 1.27)
				)
				(justify mirror)
			)
		)
		(property "Value" ""
			(at 0 0 90)
			(layer "B.Fab")
			(effects
				(font
					(size 1.27 1.27)
				)
				(justify mirror)
			)
		)
		(duplicate_pad_numbers_are_jumpers no)
		(fp_line
			(start -0.7874 0.4064)
			(end 0.7874 0.4064)
			(stroke
				(width 0.1524)
				(type default)
			)
			(layer "B.SilkS")
		)
		(fp_line
			(start 0.7874 0.4064)
			(end 0.7874 -0.4064)
			(stroke
				(width 0.1524)
				(type default)
			)
			(layer "B.SilkS")
		)
		(fp_line
			(start -0.7874 -0.4064)
			(end -0.7874 0.4064)
			(stroke
				(width 0.1524)
				(type default)
			)
			(layer "B.SilkS")
		)
		(fp_line
			(start 0.7874 -0.4064)
			(end -0.7874 -0.4064)
			(stroke
				(width 0.1524)
				(type default)
			)
			(layer "B.SilkS")
		)
		(fp_line
			(start -0.67945 0.3048)
			(end -0.120396 0.3048)
			(stroke
				(width 0.1)
				(type default)
			)
			(layer "B.Fab")
		)
		(fp_line
			(start -0.120396 0.3048)
			(end -0.120396 0.2794)
			(stroke
				(width 0.1)
				(type default)
			)
			(layer "B.Fab")
		)
		(fp_line
			(start 0.12065 0.3048)
			(end 0.67945 0.3048)
			(stroke
				(width 0.1)
				(type default)
			)
			(layer "B.Fab")
		)
		(fp_line
			(start 0.67945 0.3048)
			(end 0.67945 -0.305054)
			(stroke
				(width 0.1)
				(type default)
			)
			(layer "B.Fab")
		)
		(fp_line
			(start -0.120396 0.2794)
			(end 0.12065 0.2794)
			(stroke
				(width 0.1)
				(type default)
			)
			(layer "B.Fab")
		)
		(fp_line
			(start 0.12065 0.2794)
			(end 0.12065 0.3048)
			(stroke
				(width 0.1)
				(type default)
			)
			(layer "B.Fab")
		)
		(fp_line
			(start -0.12065 -0.2794)
			(end -0.12065 -0.3048)
			(stroke
				(width 0.1)
				(type default)
			)
			(layer "B.Fab")
		)
		(fp_line
			(start 0.12065 -0.2794)
			(end -0.12065 -0.2794)
			(stroke
				(width 0.1)
				(type default)
			)
			(layer "B.Fab")
		)
		(fp_line
			(start -0.67945 -0.3048)
			(end -0.67945 0.3048)
			(stroke
				(width 0.1)
				(type default)
			)
			(layer "B.Fab")
		)
		(fp_line
			(start -0.12065 -0.3048)
			(end -0.67945 -0.3048)
			(stroke
				(width 0.1)
				(type default)
			)
			(layer "B.Fab")
		)
		(fp_line
			(start 0.12065 -0.305054)
			(end 0.12065 -0.2794)
			(stroke
				(width 0.1)
				(type default)
			)
			(layer "B.Fab")
		)
		(fp_line
			(start 0.67945 -0.305054)
			(end 0.12065 -0.305054)
			(stroke
				(width 0.1)
				(type default)
			)
			(layer "B.Fab")
		)
		(pad "1" smd circle
			(at 0.40005 0 90)
			(size 0 0)
			(layers "B.Cu" "B.Mask" "B.Paste")
			(net "P1V0_STBY_PLAVDD")
		)
		(pad "2" smd circle
			(at -0.40005 0 90)
			(size 0 0)
			(layers "B.Cu" "B.Mask" "B.Paste")
			(net "GND")
		)
	)
	(footprint ""
		(layer "B.Cu")
		(at 68.58 -13.462)
		(property "Reference" "R882"
			(at 0 0 0)
			(layer "B.SilkS")
			(hide yes)
			(effects
				(font
					(size 1.27 1.27)
				)
				(justify mirror)
			)
		)
		(property "Value" ""
			(at 0 0 0)
			(layer "B.Fab")
			(effects
				(font
					(size 1.27 1.27)
				)
				(justify mirror)
			)
		)
		(duplicate_pad_numbers_are_jumpers no)
		(fp_line
			(start -0.7874 -0.4064)
			(end -0.7874 0.4064)
			(stroke
				(width 0.1524)
				(type default)
			)
			(layer "B.SilkS")
		)
		(fp_line
			(start -0.7874 0.4064)
			(end 0.7874 0.4064)
			(stroke
				(width 0.1524)
				(type default)
			)
			(layer "B.SilkS")
		)
		(fp_line
			(start 0.7874 -0.4064)
			(end -0.7874 -0.4064)
			(stroke
				(width 0.1524)
				(type default)
			)
			(layer "B.SilkS")
		)
		(fp_line
			(start 0.7874 0.4064)
			(end 0.7874 -0.4064)
			(stroke
				(width 0.1524)
				(type default)
			)
			(layer "B.SilkS")
		)
		(fp_line
			(start -0.67945 -0.3048)
			(end -0.67945 0.3048)
			(stroke
				(width 0.1)
				(type default)
			)
			(layer "B.Fab")
		)
		(fp_line
			(start -0.67945 0.3048)
			(end -0.120396 0.3048)
			(stroke
				(width 0.1)
				(type default)
			)
			(layer "B.Fab")
		)
		(fp_line
			(start -0.12065 -0.3048)
			(end -0.67945 -0.3048)
			(stroke
				(width 0.1)
				(type default)
			)
			(layer "B.Fab")
		)
		(fp_line
			(start -0.12065 -0.2794)
			(end -0.12065 -0.3048)
			(stroke
				(width 0.1)
				(type default)
			)
			(layer "B.Fab")
		)
		(fp_line
			(start -0.120396 0.2794)
			(end 0.12065 0.2794)
			(stroke
				(width 0.1)
				(type default)
			)
			(layer "B.Fab")
		)
		(fp_line
			(start -0.120396 0.3048)
			(end -0.120396 0.2794)
			(stroke
				(width 0.1)
				(type default)
			)
			(layer "B.Fab")
		)
		(fp_line
			(start 0.12065 -0.305054)
			(end 0.12065 -0.2794)
			(stroke
				(width 0.1)
				(type default)
			)
			(layer "B.Fab")
		)
		(fp_line
			(start 0.12065 -0.2794)
			(end -0.12065 -0.2794)
			(stroke
				(width 0.1)
				(type default)
			)
			(layer "B.Fab")
		)
		(fp_line
			(start 0.12065 0.2794)
			(end 0.12065 0.3048)
			(stroke
				(width 0.1)
				(type default)
			)
			(layer "B.Fab")
		)
		(fp_line
			(start 0.12065 0.3048)
			(end 0.67945 0.3048)
			(stroke
				(width 0.1)
				(type default)
			)
			(layer "B.Fab")
		)
		(fp_line
			(start 0.67945 -0.305054)
			(end 0.12065 -0.305054)
			(stroke
				(width 0.1)
				(type default)
			)
			(layer "B.Fab")
		)
		(fp_line
			(start 0.67945 0.3048)
			(end 0.67945 -0.305054)
			(stroke
				(width 0.1)
				(type default)
			)
			(layer "B.Fab")
		)
		(pad "1" smd circle
			(at 0.40005 0 180)
			(size 0 0)
			(layers "B.Cu" "B.Mask" "B.Paste")
			(net "REAR_AC_PWR_BTN")
		)
		(pad "2" smd circle
			(at -0.40005 0 180)
			(size 0 0)
			(layers "B.Cu" "B.Mask" "B.Paste")
			(net "REAR_AC_PWR_BMC_BTN_N")
		)
	)
)
